(kicad_pcb
	(version 20241229)
	(generator "pcbnew")
	(generator_version "9.0")
	(general
		(thickness 1.62)
		(legacy_teardrops no)
	)
	(paper "A3")
	(title_block
		(title "COM Express 7 Baseboard")
		(date "2025-02-04")
		(rev "1.1.2")
		(company "Antmicro Ltd")
		(comment 1 "www.antmicro.com")
		(comment 9 "footprint 244 of 802 (U43), pads 119-144 of 144")
	)
	(layers
		(0 "F.Cu" signal)
		(4 "In1.Cu" signal)
		(6 "In2.Cu" signal)
		(8 "In3.Cu" signal)
		(10 "In4.Cu" signal)
		(12 "In5.Cu" signal)
		(14 "In6.Cu" signal)
		(2 "B.Cu" signal)
		(9 "F.Adhes" user "F.Adhesive")
		(11 "B.Adhes" user "B.Adhesive")
		(13 "F.Paste" user)
		(15 "B.Paste" user)
		(5 "F.SilkS" user "F.Silkscreen")
		(7 "B.SilkS" user "B.Silkscreen")
		(1 "F.Mask" user)
		(3 "B.Mask" user)
		(17 "Dwgs.User" user "User.Drawings")
		(19 "Cmts.User" user "User.Comments")
		(21 "Eco1.User" user "User.Eco1")
		(23 "Eco2.User" user "User.Eco2")
		(25 "Edge.Cuts" user)
		(27 "Margin" user)
		(31 "F.CrtYd" user "F.Courtyard")
		(29 "B.CrtYd" user "B.Courtyard")
		(35 "F.Fab" user)
		(33 "B.Fab" user)
	)
	(footprint "antmicro-footprints:BGA-144_12x12_13.05x13.05mm_P1.0mm"
		(layer "F.Cu")
		(at 150.95 137.36 -90)
		(property "Reference" "U43"
			(at 7.9 4.65 180)
			(layer "F.SilkS")
			(effects
				(font
					(size 0.7 0.7)
					(thickness 0.15)
				)
				(justify right bottom)
			)
		)
		(property "Value" "TLK10232CTR"
			(at 0 7.525 90)
			(layer "F.Fab")
			(effects
				(font
					(size 0.7 0.7)
					(thickness 0.15)
				)
				(justify right bottom)
			)
		)
		(property "Datasheet" "https://www.ti.com/lit/ds/symlink/tlk10232.pdf?ts=1712150848075&ref_url=https%253A%252F%252Fwww.mouser.pl%252F"
			(at 0 0 270)
			(layer "F.Fab")
			(hide yes)
			(effects
				(font
					(size 1.27 1.27)
					(thickness 0.15)
				)
			)
		)
		(property "Author" "Antmicro"
			(at 13.59 288.31 0)
			(layer "F.Fab")
			(hide yes)
			(effects
				(font
					(size 1 1)
					(thickness 0.15)
				)
			)
		)
		(property "License" "Apache-2.0"
			(at 13.59 288.31 0)
			(layer "F.Fab")
			(hide yes)
			(effects
				(font
					(size 1 1)
					(thickness 0.15)
				)
			)
		)
		(property "MPN" "TLK10232CTR"
			(at 13.59 288.31 0)
			(layer "F.Fab")
			(hide yes)
			(effects
				(font
					(size 1 1)
					(thickness 0.15)
				)
			)
		)
		(property "Manufacturer" "Texas Instruments"
			(at 13.59 288.31 0)
			(layer "F.Fab")
			(hide yes)
			(effects
				(font
					(size 1 1)
					(thickness 0.15)
				)
			)
		)
		(sheetname "KR to SFI #1")
		(sheetfile "kr_sfi.kicad_sch")
		(attr smd)
		(pad "K11" smd circle
			(at 4.5 3.5 270)
			(size 0.5 0.5)
			(layers "F.Cu" "F.Mask" "F.Paste")
			(net 1 "GND")
			(pinfunction "GND")
			(pintype "passive")
			(solder_mask_margin 0.05)
			(teardrops
				(best_length_ratio 0.4)
				(max_length 1)
				(best_width_ratio 0.9)
				(max_width 2)
				(curved_edges yes)
				(filter_ratio 0.9)
				(enabled yes)
				(allow_two_segments yes)
				(prefer_zone_connections yes)
			)
		)
		(pad "K12" smd circle
			(at 5.5 3.5 270)
			(size 0.5 0.5)
			(layers "F.Cu" "F.Mask" "F.Paste")
			(net 666 "/2xSFP+/KR to SFI #1/SFI_R.TX+")
			(pinfunction "HSTXB+")
			(pintype "output")
			(solder_mask_margin 0.05)
			(teardrops
				(best_length_ratio 0.4)
				(max_length 1)
				(best_width_ratio 0.9)
				(max_width 2)
				(curved_edges yes)
				(filter_ratio 0.9)
				(enabled yes)
				(allow_two_segments yes)
				(prefer_zone_connections yes)
			)
		)
		(pad "L1" smd circle
			(at -5.5 4.5 270)
			(size 0.5 0.5)
			(layers "F.Cu" "F.Mask" "F.Paste")
			(net 823 "unconnected-(U43B-INB2+-PadL1)")
			(pinfunction "INB2+")
			(pintype "input+no_connect")
			(solder_mask_margin 0.05)
			(teardrops
				(best_length_ratio 0.4)
				(max_length 1)
				(best_width_ratio 0.9)
				(max_width 2)
				(curved_edges yes)
				(filter_ratio 0.9)
				(enabled yes)
				(allow_two_segments yes)
				(prefer_zone_connections yes)
			)
		)
		(pad "L2" smd circle
			(at -4.5 4.5 270)
			(size 0.5 0.5)
			(layers "F.Cu" "F.Mask" "F.Paste")
			(net 824 "unconnected-(U43B-INB1--PadL2)")
			(pinfunction "INB1-")
			(pintype "input+no_connect")
			(solder_mask_margin 0.05)
			(teardrops
				(best_length_ratio 0.4)
				(max_length 1)
				(best_width_ratio 0.9)
				(max_width 2)
				(curved_edges yes)
				(filter_ratio 0.9)
				(enabled yes)
				(allow_two_segments yes)
				(prefer_zone_connections yes)
			)
		)
		(pad "L3" smd circle
			(at -3.5 4.5 270)
			(size 0.5 0.5)
			(layers "F.Cu" "F.Mask" "F.Paste")
			(net 1 "GND")
			(pinfunction "GND")
			(pintype "passive")
			(solder_mask_margin 0.05)
			(teardrops
				(best_length_ratio 0.4)
				(max_length 1)
				(best_width_ratio 0.9)
				(max_width 2)
				(curved_edges yes)
				(filter_ratio 0.9)
				(enabled yes)
				(allow_two_segments yes)
				(prefer_zone_connections yes)
			)
		)
		(pad "L4" smd circle
			(at -2.5 4.5 270)
			(size 0.5 0.5)
			(layers "F.Cu" "F.Mask" "F.Paste")
			(net 1 "GND")
			(pinfunction "GND")
			(pintype "passive")
			(solder_mask_margin 0.05)
			(teardrops
				(best_length_ratio 0.4)
				(max_length 1)
				(best_width_ratio 0.9)
				(max_width 2)
				(curved_edges yes)
				(filter_ratio 0.9)
				(enabled yes)
				(allow_two_segments yes)
				(prefer_zone_connections yes)
			)
		)
		(pad "L5" smd circle
			(at -1.5 4.5 270)
			(size 0.5 0.5)
			(layers "F.Cu" "F.Mask" "F.Paste")
			(net 825 "unconnected-(U43B-OUTB2--PadL5)")
			(pinfunction "OUTB2-")
			(pintype "output+no_connect")
			(solder_mask_margin 0.05)
			(teardrops
				(best_length_ratio 0.4)
				(max_length 1)
				(best_width_ratio 0.9)
				(max_width 2)
				(curved_edges yes)
				(filter_ratio 0.9)
				(enabled yes)
				(allow_two_segments yes)
				(prefer_zone_connections yes)
			)
		)
		(pad "L6" smd circle
			(at -0.5 4.5 270)
			(size 0.5 0.5)
			(layers "F.Cu" "F.Mask" "F.Paste")
			(net 826 "unconnected-(U43B-OUTB2+-PadL6)")
			(pinfunction "OUTB2+")
			(pintype "output+no_connect")
			(solder_mask_margin 0.05)
			(teardrops
				(best_length_ratio 0.4)
				(max_length 1)
				(best_width_ratio 0.9)
				(max_width 2)
				(curved_edges yes)
				(filter_ratio 0.9)
				(enabled yes)
				(allow_two_segments yes)
				(prefer_zone_connections yes)
			)
		)
		(pad "L7" smd circle
			(at 0.5 4.5 270)
			(size 0.5 0.5)
			(layers "F.Cu" "F.Mask" "F.Paste")
			(net 1 "GND")
			(pinfunction "GND")
			(pintype "passive")
			(solder_mask_margin 0.05)
			(teardrops
				(best_length_ratio 0.4)
				(max_length 1)
				(best_width_ratio 0.9)
				(max_width 2)
				(curved_edges yes)
				(filter_ratio 0.9)
				(enabled yes)
				(allow_two_segments yes)
				(prefer_zone_connections yes)
			)
		)
		(pad "L8" smd circle
			(at 1.5 4.5 270)
			(size 0.5 0.5)
			(layers "F.Cu" "F.Mask" "F.Paste")
			(net 738 "Net-(U43B-LS_OK_{IN_B})")
			(pinfunction "LS_OK_{IN_B}")
			(pintype "input")
			(solder_mask_margin 0.05)
			(teardrops
				(best_length_ratio 0.4)
				(max_length 1)
				(best_width_ratio 0.9)
				(max_width 2)
				(curved_edges yes)
				(filter_ratio 0.9)
				(enabled yes)
				(allow_two_segments yes)
				(prefer_zone_connections yes)
			)
		)
		(pad "L9" smd circle
			(at 2.5 4.5 270)
			(size 0.5 0.5)
			(layers "F.Cu" "F.Mask" "F.Paste")
			(net 658 "Net-(U43C-PRTAD2)")
			(pinfunction "PRTAD2")
			(pintype "input")
			(solder_mask_margin 0.05)
			(teardrops
				(best_length_ratio 0.4)
				(max_length 1)
				(best_width_ratio 0.9)
				(max_width 2)
				(curved_edges yes)
				(filter_ratio 0.9)
				(enabled yes)
				(allow_two_segments yes)
				(prefer_zone_connections yes)
			)
		)
		(pad "L10" smd circle
			(at 3.5 4.5 270)
			(size 0.5 0.5)
			(layers "F.Cu" "F.Mask" "F.Paste")
			(net 653 "Net-(U43C-TESTEN)")
			(pinfunction "TESTEN")
			(pintype "input")
			(solder_mask_margin 0.05)
			(teardrops
				(best_length_ratio 0.4)
				(max_length 1)
				(best_width_ratio 0.9)
				(max_width 2)
				(curved_edges yes)
				(filter_ratio 0.9)
				(enabled yes)
				(allow_two_segments yes)
				(prefer_zone_connections yes)
			)
		)
		(pad "L11" smd circle
			(at 4.5 4.5 270)
			(size 0.5 0.5)
			(layers "F.Cu" "F.Mask" "F.Paste")
			(net 1 "GND")
			(pinfunction "GND")
			(pintype "passive")
			(solder_mask_margin 0.05)
			(teardrops
				(best_length_ratio 0.4)
				(max_length 1)
				(best_width_ratio 0.9)
				(max_width 2)
				(curved_edges yes)
				(filter_ratio 0.9)
				(enabled yes)
				(allow_two_segments yes)
				(prefer_zone_connections yes)
			)
		)
		(pad "L12" smd circle
			(at 5.5 4.5 270)
			(size 0.5 0.5)
			(layers "F.Cu" "F.Mask" "F.Paste")
			(net 685 "/2xSFP+/KR to SFI #1/SFI_R.TX-")
			(pinfunction "HSTXB-")
			(pintype "output")
			(solder_mask_margin 0.05)
			(teardrops
				(best_length_ratio 0.4)
				(max_length 1)
				(best_width_ratio 0.9)
				(max_width 2)
				(curved_edges yes)
				(filter_ratio 0.9)
				(enabled yes)
				(allow_two_segments yes)
				(prefer_zone_connections yes)
			)
		)
		(pad "M1" smd circle
			(at -5.5 5.5 270)
			(size 0.5 0.5)
			(layers "F.Cu" "F.Mask" "F.Paste")
			(net 827 "unconnected-(U43B-INB2--PadM1)")
			(pinfunction "INB2-")
			(pintype "input+no_connect")
			(solder_mask_margin 0.05)
			(teardrops
				(best_length_ratio 0.4)
				(max_length 1)
				(best_width_ratio 0.9)
				(max_width 2)
				(curved_edges yes)
				(filter_ratio 0.9)
				(enabled yes)
				(allow_two_segments yes)
				(prefer_zone_connections yes)
			)
		)
		(pad "M2" smd circle
			(at -4.5 5.5 270)
			(size 0.5 0.5)
			(layers "F.Cu" "F.Mask" "F.Paste")
			(net 1 "GND")
			(pinfunction "GND")
			(pintype "passive")
			(solder_mask_margin 0.05)
			(teardrops
				(best_length_ratio 0.4)
				(max_length 1)
				(best_width_ratio 0.9)
				(max_width 2)
				(curved_edges yes)
				(filter_ratio 0.9)
				(enabled yes)
				(allow_two_segments yes)
				(prefer_zone_connections yes)
			)
		)
		(pad "M3" smd circle
			(at -3.5 5.5 270)
			(size 0.5 0.5)
			(layers "F.Cu" "F.Mask" "F.Paste")
			(net 828 "unconnected-(U43B-INB3+-PadM3)")
			(pinfunction "INB3+")
			(pintype "input+no_connect")
			(solder_mask_margin 0.05)
			(teardrops
				(best_length_ratio 0.4)
				(max_length 1)
				(best_width_ratio 0.9)
				(max_width 2)
				(curved_edges yes)
				(filter_ratio 0.9)
				(enabled yes)
				(allow_two_segments yes)
				(prefer_zone_connections yes)
			)
		)
		(pad "M4" smd circle
			(at -2.5 5.5 270)
			(size 0.5 0.5)
			(layers "F.Cu" "F.Mask" "F.Paste")
			(net 829 "unconnected-(U43B-INB3--PadM4)")
			(pinfunction "INB3-")
			(pintype "input+no_connect")
			(solder_mask_margin 0.05)
			(teardrops
				(best_length_ratio 0.4)
				(max_length 1)
				(best_width_ratio 0.9)
				(max_width 2)
				(curved_edges yes)
				(filter_ratio 0.9)
				(enabled yes)
				(allow_two_segments yes)
				(prefer_zone_connections yes)
			)
		)
		(pad "M5" smd circle
			(at -1.5 5.5 270)
			(size 0.5 0.5)
			(layers "F.Cu" "F.Mask" "F.Paste")
			(net 1 "GND")
			(pinfunction "GND")
			(pintype "passive")
			(solder_mask_margin 0.05)
			(teardrops
				(best_length_ratio 0.4)
				(max_length 1)
				(best_width_ratio 0.9)
				(max_width 2)
				(curved_edges yes)
				(filter_ratio 0.9)
				(enabled yes)
				(allow_two_segments yes)
				(prefer_zone_connections yes)
			)
		)
		(pad "M6" smd circle
			(at -0.5 5.5 270)
			(size 0.5 0.5)
			(layers "F.Cu" "F.Mask" "F.Paste")
			(net 830 "unconnected-(U43B-OUTB3--PadM6)")
			(pinfunction "OUTB3-")
			(pintype "output+no_connect")
			(solder_mask_margin 0.05)
			(teardrops
				(best_length_ratio 0.4)
				(max_length 1)
				(best_width_ratio 0.9)
				(max_width 2)
				(curved_edges yes)
				(filter_ratio 0.9)
				(enabled yes)
				(allow_two_segments yes)
				(prefer_zone_connections yes)
			)
		)
		(pad "M7" smd circle
			(at 0.5 5.5 270)
			(size 0.5 0.5)
			(layers "F.Cu" "F.Mask" "F.Paste")
			(net 831 "unconnected-(U43B-OUTB3+-PadM7)")
			(pinfunction "OUTB3+")
			(pintype "output+no_connect")
			(solder_mask_margin 0.05)
			(teardrops
				(best_length_ratio 0.4)
				(max_length 1)
				(best_width_ratio 0.9)
				(max_width 2)
				(curved_edges yes)
				(filter_ratio 0.9)
				(enabled yes)
				(allow_two_segments yes)
				(prefer_zone_connections yes)
			)
		)
		(pad "M8" smd circle
			(at 1.5 5.5 270)
			(size 0.5 0.5)
			(layers "F.Cu" "F.Mask" "F.Paste")
			(net 661 "Net-(U43C-PRTAD4)")
			(pinfunction "PRTAD4")
			(pintype "input")
			(solder_mask_margin 0.05)
			(teardrops
				(best_length_ratio 0.4)
				(max_length 1)
				(best_width_ratio 0.9)
				(max_width 2)
				(curved_edges yes)
				(filter_ratio 0.9)
				(enabled yes)
				(allow_two_segments yes)
				(prefer_zone_connections yes)
			)
		)
		(pad "M9" smd circle
			(at 2.5 5.5 270)
			(size 0.5 0.5)
			(layers "F.Cu" "F.Mask" "F.Paste")
			(net 663 "Net-(U43C-ST)")
			(pinfunction "ST")
			(pintype "input")
			(solder_mask_margin 0.05)
			(teardrops
				(best_length_ratio 0.4)
				(max_length 1)
				(best_width_ratio 0.9)
				(max_width 2)
				(curved_edges yes)
				(filter_ratio 0.9)
				(enabled yes)
				(allow_two_segments yes)
				(prefer_zone_connections yes)
			)
		)
		(pad "M10" smd circle
			(at 3.5 5.5 270)
			(size 0.5 0.5)
			(layers "F.Cu" "F.Mask" "F.Paste")
			(net 108 "/2xSFP+/KR to SFI #1/REFCLK+")
			(pinfunction "REFCLK0+")
			(pintype "input")
			(solder_mask_margin 0.05)
			(teardrops
				(best_length_ratio 0.4)
				(max_length 1)
				(best_width_ratio 0.9)
				(max_width 2)
				(curved_edges yes)
				(filter_ratio 0.9)
				(enabled yes)
				(allow_two_segments yes)
				(prefer_zone_connections yes)
			)
		)
		(pad "M11" smd circle
			(at 4.5 5.5 270)
			(size 0.5 0.5)
			(layers "F.Cu" "F.Mask" "F.Paste")
			(net 110 "/2xSFP+/KR to SFI #1/REFCLK-")
			(pinfunction "REFCLK0-")
			(pintype "input")
			(solder_mask_margin 0.05)
			(teardrops
				(best_length_ratio 0.4)
				(max_length 1)
				(best_width_ratio 0.9)
				(max_width 2)
				(curved_edges yes)
				(filter_ratio 0.9)
				(enabled yes)
				(allow_two_segments yes)
				(prefer_zone_connections yes)
			)
		)
		(pad "M12" smd circle
			(at 5.5 5.5 270)
			(size 0.5 0.5)
			(layers "F.Cu" "F.Mask" "F.Paste")
			(net 1 "GND")
			(pinfunction "GND")
			(pintype "passive")
			(solder_mask_margin 0.05)
			(teardrops
				(best_length_ratio 0.4)
				(max_length 1)
				(best_width_ratio 0.9)
				(max_width 2)
				(curved_edges yes)
				(filter_ratio 0.9)
				(enabled yes)
				(allow_two_segments yes)
				(prefer_zone_connections yes)
			)
		)
	)
)
